#ISCELL
  mstr_misc prelim *
  *
#ISCELL
  mstr_symbols design_note *
  *
#ISCELL
  mstr_symbols intel_corp_bpage *
  *
#ISCELL
  mstr_symbols gnd *
  page75_i10
#ISCELL
  mstr_symbols gnd *
  page75_i11
#ISCELL
  mstr_symbols gnd *
  page75_i12
#ISCELL
  mstr_symbols gnd *
  page75_i13
#ISCELL
  mstr_symbols gnd *
  page75_i14
#ISCELL
  mstr_symbols gnd *
  page75_i15
#ISCELL
  mstr_symbols gnd *
  page75_i16
#CELL
  chpset_lib skx_ext_b *
  page75_i17
#CELL
  chpset_lib skx_ext_b *
  page75_i18
#CELL
  chpset_lib skx_ext_b *
  page75_i19
#CELL
  chpset_lib skx_ext_b *
  page75_i20
#ISCELL
  mstr_symbols gnd *
  page75_i9
